FILE_TYPE = CONNECTIVITY;
{Allegro Design Entry HDL 17.4-2019 S026 (4007227) 1/17/2022}
"PAGE_NUMBER" = 54;
0"NC";
1"GND\g";
2"PVDD18_S5_P1\g";
3"GND\g";
4"GND\g";
5"GND\g";
6"GND\g";
7"GND\g";
8"GND\g";
9"GND\g";
10"GND\g";
11"CPU1_BP0";
12"CPU1_BP1";
13"CPU1_BP3";
14"PVDD18_S5_P1\g";
15"APML_CPU1_ALERT_N";
16"CPU1_BP2";
17"P3V3_AUX\g";
18"GND\g";
19"GND\g";
20"PVDD18_S5_P1\g";
21"CPU1_XTRIG_L7";
22"CPU1_PROCHOT_N";
23"CPU1_XTRIG_L5";
24"CPU1_XTRIG_L4";
25"CPU1_XTRIG_L6";
26"CPU1_THERMTRIP_N";
27"CPU1_SP5R1";
28"CPU1_SP5R4";
29"TP_CPU1_TEST6_CCD2";
30"TP_CPU1_TEST6_CCD0";
31"CPU1_BP2";
32"CPU1_BP0";
33"CPU1_XTRIG_R2_L7";
34"CPU1_XTRIG_R2_L5";
35"APML_CPU1_ALERT_R_N";
36"CPU1_CORETYPE0";
37"VSENSE_VSS_SENSE_B_P1";
38"VSENSE_PVDDCR_CPU1_P1_DP";
39"TP_CPU1_TEST4_CCD9";
40"CPU1_PROCHOT_N";
41"NC_CPU1_AZ_SYNC";
42"NC_CPU1_AZ_SDIN0";
43"NC_CPU1_AZ_RST_N";
44"NC_CPU1_AZ_SDIN1";
45"NC_CPU1_AZ_SDOUT";
46"NC_CPU1_AZ_SDIN2";
47"NC_CPU1_AZ_BITCLK";
48"CPU1_BP3";
49"CPU1_BP1";
50"TP_CPU1_TEST6_X3D3";
51"TP_CPU1_TEST6_X3D2";
52"TP_CPU1_TEST6_X3D1";
53"TP_CPU1_TEST6_X3D0";
54"TP_CPU1_TEST4_CCD6";
55"TP_CPU1_TEST4_CCD5";
56"TP_CPU1_TEST4_CCD4";
57"TP_CPU1_TEST6_IOD";
58"TP_CPU1_TEST4_CCD3";
59"TP_CPU1_TEST4_CCD2";
60"TP_CPU1_TEST4_CCD1";
61"TP_CPU1_TEST6_CCD3";
62"TP_CPU1_TEST4_CCD0";
63"TP_CPU1_TEST6_X3D5";
64"TP_CPU1_TEST6_CCD1";
65"TP_CPU1_TEST6_X3D4";
66"TP_CPU1_TEST5_CCD11";
67"TP_CPU1_TEST4_CCD11";
68"TP_CPU1_TEST5_CCD10";
69"TP_CPU1_TEST4_CCD10";
70"TP_CPU1_TEST4_CCD8";
71"TP_CPU1_TEST5_CCD9";
72"TP_CPU1_TEST4_CCD7";
73"TP_CPU1_TEST5_CCD8";
74"TP_CPU1_TEST5_CCD7";
75"TP_CPU1_TEST5_CCD6";
76"TP_CPU1_TEST5_CCD5";
77"TP_CPU1_TEST5_CCD4";
78"TP_CPU1_TEST4_IOD";
79"TP_CPU1_TEST5_CCD3";
80"TP_CPU1_TEST5_CCD2";
81"TP_CPU1_TEST5_CCD1";
82"TP_CPU1_TEST5_CCD0";
83"TP_CPU1_UART1_RX";
84"TP_CPU1_UART0_CTS_N";
85"TP_CPU1_UART0_TX";
86"TP_CPU1_UART0_RTS_N";
87"TP_CPU1_UART0_RX";
88"TP_CPU1_TEST41_IOD";
89"TP_CPU1_TEST5_IOD";
90"TP_CPU1_UART0_INTR";
91"SMB_APML_CPU1_SCL";
92"SMB_APML_CPU1_SDA";
93"JTAG_CPU1_DBREQ_N";
94"JTAG_CPU1_TMS";
95"JTAG_CPU1_TCK";
96"JTAG_CPU1_TRST_N";
97"JTAG_CPU1_TDI";
98"SVID_PVDDCR_CPU0_P1_SVTO";
99"FM_P1_PCC1_N";
100"CPU1_CORETYPE2";
101"CPU1_CORETYPE1";
102"CPU1_SP5R3";
103"CPU1_SP5R2";
104"CPU1_SP5R1";
105"CPU1_SA1";
106"CPU1_SA0";
107"PRSNT_CPU1_N";
108"TP_CPU1_TEST47_CCD3";
109"TP_CPU1_TEST47_IOD1";
110"TP_CPU1_TEST47_IOD0";
111"TP_CPU1_TEST47_CCD2";
112"TP_CPU1_TEST47_CCD1";
113"TP_CPU1_TEST47_CCD0";
114"VSENSE_PVDDCR_CPU0_P1_DP";
115"VSENSE_PVDDCR_SOC_P1_DP";
116"TP_VSENSE_PVDD33_S5_P1";
117"VSENSE_PVDD18_S5_P1_DP";
118"VSENSE_PVDD11_S3_P1_DP";
119"VSENSE_PVDDIO_P1_DP";
120"VSENSE_PVDD18_S5_P1_DN";
121"VSENSE_VSS_SENSE_C_P1";
122"VSENSE_VSS_SENSE_A_P1";
123"TP_CPU1_TEST50_IOD";
124"CPU1_CORETYPE2";
125"CPU1_CORETYPE1";
126"CPU1_CORETYPE0";
127"CPU1_SP5R4";
128"CPU1_SP5R3";
129"CPU1_SP5R2";
130"CPU1_SA1";
131"CPU1_SA0";
132"SVID_PVDDCR_CPU1_P1_SVTO";
133"FM_P1_PCC0_N";
134"JTAG_CPU1_TDO";
135"JTAG_CPU1_R_TDO";
136"SVID_PVDDCR_CPU0_P1_SVD";
137"SVID_PVDDCR_CPU0_P1_SVD_R";
138"SVID_PVDDCR_CPU0_P1_SVC";
139"SVID_PVDDCR_CPU0_P1_SVC_R";
140"SVID_PVDDCR_CPU1_P1_SVD";
141"SVID_PVDDCR_CPU1_P1_SVD_R";
142"SVID_PVDDCR_CPU1_P1_SVC";
143"SVID_PVDDCR_CPU1_P1_SVC_R";
144"CPU1_XTRIG_L5";
145"CPU1_XTRIG_L4";
146"CPU1_XTRIG_R2_L4";
147"CPU1_XTRIG_L7";
148"CPU1_XTRIG_L6";
149"CPU1_XTRIG_R2_L6";
150"CPU1_XTRIG_L6";
151"JTAG_CPU1_TDI";
152"JTAG_CPU1_TDO";
153"JTAG_CPU1_DBREQ_N";
154"JTAG_CPU1_TMS";
155"JTAG_CPU1_TCK";
156"JTAG_CPU1_TRST_N";
157"APML_CPU1_ALERT_N";
158"CPU1_THERMTRIP_R_N";
159"CPU1_THERMTRIP_N";
160"CPU1_XTRIG_L7";
161"CPU1_XTRIG_L5";
162"CPU1_XTRIG_L4";
163"CPU1_XTRIG_R1_L7";
164"CPU1_XTRIG_R1_L6";
165"CPU1_XTRIG_R1_L5";
166"CPU1_XTRIG_R1_L4";
167"CPU1_BP3";
168"CPU1_BP2";
169"CPU1_BP1";
170"CPU1_BP0";
%"UNIVERSAL_POWER"
"1","(-150,6225)","0","pure_quanta_power","I156";
;
HDL_POWER"PVDD18_S5_P1"
CDS_LIB"pure_quanta_power";
"A"14;
%"GENOA_SP5"
"20","(-4650,3750)","0","pure_quanta","I190";
;
LOCATION"U26"
$SEC"20"
CDS_SEC"20"
PART_TYPE"SMLF"
VALUE"SOCKET6096_13568-001"
MATERIAL"IO"
NEEDS_NO_SIZE"TRUE"
CDS_LMAN_SYM_OUTLINE"-600,2425,600,-2425"
CDS_LIB"pure_quanta"
PART_NUMBER"DGA^6000030";
"CORETYPE2"
$PN"D68"100;
"BP3"
$PN"A62"48;
"BP2"
$PN"A63"31;
"BP1"
$PN"C62"49;
"BP0"
$PN"C63"32;
"TEST41_IOD"
$PN"W31"88;
"TEST47_CCD3"
$PN"E32"108;
"TEST6_CCD0"
$PN"AA46"30;
"TEST6_X3D3"
$PN"CJ52"50;
"TEST6_X3D2"
$PN"AA29"51;
"TEST47_IOD1"
$PN"D7"109;
"TEST6_X3D1"
$PN"CJ29"52;
"TEST47_IOD0"
$PN"B58"110;
"TEST6_X3D0"
$PN"AA47"53;
"TEST5_CCD11"
$PN"Y29"66;
"TEST4_CCD11"
$PN"AA28"67;
"TEST5_CCD10"
$PN"CK47"68;
"TEST4_CCD9"
$PN"CK30"39;
"TEST4_CCD10"
$PN"CJ47"69;
"TEST47_CCD2"
$PN"CK46"111;
"TEST4_CCD8"
$PN"AA48"70;
"TEST5_CCD9"
$PN"CK29"71;
"TEST47_CCD1"
$PN"CJ24"112;
"TEST4_CCD7"
$PN"AA27"72;
"TEST50_IOD"
$PN"B61"123;
"TEST5_CCD8"
$PN"Y47"73;
"TEST47_CCD0"
$PN"B60"113;
"TEST4_CCD6"
$PN"CJ50"54;
"TEST5_CCD7"
$PN"AA26"74;
"TEST4_CCD5"
$PN"CJ26"55;
"TEST5_CCD6"
$PN"CJ51"75;
"TEST4_CCD4"
$PN"AA52"56;
"TEST5_CCD5"
$PN"CJ25"76;
"TEST6_IOD"
$PN"AA49"57;
"TEST4_CCD3"
$PN"AA30"58;
"TEST5_CCD4"
$PN"AA53"77;
"TEST5_IOD"
$PN"AA24"89;
"TEST4_CCD2"
$PN"CJ48"59;
"TEST4_IOD"
$PN"AA25"78;
"TEST5_CCD3"
$PN"Y30"79;
"TEST4_CCD1"
$PN"CJ28"60;
"TEST5_CCD2"
$PN"CJ49"80;
"TEST6_CCD3"
$PN"Y46"61;
"TEST4_CCD0"
$PN"AA50"62;
"TEST5_CCD1"
$PN"CJ27"81;
"TEST6_CCD2"
$PN"CJ46"29;
"TEST6_X3D5"
$PN"CJ53"63;
"TEST5_CCD0"
$PN"AA51"82;
"TEST6_CCD1"
$PN"CJ30"64;
"TEST6_X3D4"
$PN"AA23"65;
"VDDCR_CPU0_SENSE"
$PN"C2"114;
"VDDCR_CPU1_SENSE"
$PN"DG3"38;
"VDDCR_SOC_SENSE"
$PN"B3"115;
"VDD_33_S5_SENSE"
$PN"BP53"116;
"VDD_18_S5_SENSE"
$PN"C74"117;
"VDD_11_S3_SENSE"
$PN"DH3"118;
"VDDIO_SENSE"
$PN"BR53"119;
"VSS_SENSE_D"
$PN"B73"120;
"VSS_SENSE_C"
$PN"DJ3"121;
"VSS_SENSE_B"
$PN"BR54"37;
"VSS_SENSE_A"
$PN"C3"122;
"UART1_TXD||AGPIO142"
$PN"DJ32"0;
"UART1_RXD||AGPIO141"
$PN"DH33"83;
"RTC_LDO_SELECT"
$PN"DH8"1;
"TCK"
$PN"B17"95;
"SP5R1"
$PN"C19"104;
"AZ_SDIN1||SW_MCLK"
$PN"D33"44;
"AZ_SDIN0||SW_MDATA3"
$PN"C33"42;
"AZ_RST_L||SW_MDATA1"
$PN"A34"43;
"AZ_SDOUT||SW_MDATA2"
$PN"A32"45;
"AZ_SDIN2||SW_MDATA0"
$PN"A33"46;
"UART0_CTS_L||UART2_TXD||AGPIO135"
$PN"DJ33"84;
"UART0_TXD||AGPIO138"
$PN"DJ34"85;
"UART0_INTR||AGPIO139"
$PN"DG34"90;
"UART0_RTS_L||UART2_RXD||AGPIO137"
$PN"DF34"86;
"UART0_RXD||AGPIO136"
$PN"DG35"87;
"SVC1"
$PN"DJ72"142;
"SVT1"
$PN"DG73"132;
"SVC0"
$PN"A23"138;
"SVD1"
$PN"DH72"140;
"SVT0"
$PN"B21"98;
"SVD0"
$PN"A22"136;
"AZ_SYNC"
$PN"D32"41;
"AZ_BITCLK"
$PN"C32"47;
"PCC1_L \B"
$PN"DG72"99;
"PCC0_L \B"
$PN"C22"133;
"SP5R4"
$PN"DH10"28;
"SP5R3"
$PN"DH73"102;
"SP5R2"
$PN"C68"103;
"CORETYPE1"
$PN"B69"101;
"CORETYPE0"
$PN"C70"36;
"SA1"
$PN"DJ56"105;
"XTRIG_L7 \B"
$PN"A65"33;
"XTRIG_L6 \B"
$PN"A66"149;
"XTRIG_L5 \B"
$PN"C65"34;
"XTRIG_L4 \B"
$PN"C66"146;
"TRST_L \B"
$PN"A17"96;
"TMS"
$PN"A16"94;
"THERMTRIP_L \B"
$PN"DJ9"159;
"TDO"
$PN"C18"135;
"TDI"
$PN"C17"97;
"SID"
$PN"DH71"92;
"SIC"
$PN"DJ71"91;
"SA0"
$PN"DJ55"106;
"PROCHOT_L \B"
$PN"A69"40;
"DBREQ_L \B"
$PN"C16"93;
"CPU_PRESENT_L"
$PN"B66"107;
"ALERT_L \B"
$PN"A68"157;
%"Q_RES"
"1","(-6100,4825)","2","pure_quanta","I203";
;
LOCATION"R529"
$SEC"1"
CDS_SEC"1"
VALUE"0"
CDS_LIB"pure_quanta"
WATTAGE"1/16W"
MATERIAL"CHIP"
TOLERANCE"5%"
PACK_TYPE"0402LF"
PART_NUMBER"CS00002JB13";
"B"
$PN"2"134;
"A"
$PN"1"135;
%"TP"
"1","(-6150,1900)","6","pure_quanta","I237";
;
LOCATION"TP20"
$SEC"1"
CDS_SEC"1"
MATERIAL"NA"
PACK_TYPE"TP"
CDS_LIB"pure_quanta"
PART_NUMBER"TP30";
"TP \B"
$PN"1"
$PIN_NUMBER"?"115;
%"TP"
"1","(-6225,1900)","6","pure_quanta","I238";
;
LOCATION"TP19"
$SEC"1"
CDS_SEC"1"
MATERIAL"NA"
PACK_TYPE"TP"
CDS_LIB"pure_quanta"
PART_NUMBER"TP30";
"TP \B"
$PN"1"
$PIN_NUMBER"?"117;
%"UNIVERSAL_GND"
"1","(-5650,1225)","0","pure_quanta_power","I239";
;
CDS_LIB"pure_quanta_power"
HDL_POWER"GND";
"A"1;
%"TP"
"1","(-6325,1900)","6","pure_quanta","I240";
;
LOCATION"TP18"
$SEC"1"
CDS_SEC"1"
MATERIAL"NA"
PACK_TYPE"TP"
CDS_LIB"pure_quanta"
PART_NUMBER"TP30";
"TP \B"
$PN"1"
$PIN_NUMBER"?"118;
%"TP"
"1","(-6400,1900)","6","pure_quanta","I241";
;
LOCATION"TP17"
$SEC"1"
CDS_SEC"1"
MATERIAL"NA"
PACK_TYPE"TP"
CDS_LIB"pure_quanta"
PART_NUMBER"TP30";
"TP \B"
$PN"1"
$PIN_NUMBER"?"114;
%"TP"
"1","(-6475,1900)","6","pure_quanta","I242";
;
LOCATION"TP16"
$SEC"1"
CDS_SEC"1"
MATERIAL"NA"
PACK_TYPE"TP"
CDS_LIB"pure_quanta"
PART_NUMBER"TP30";
"TP \B"
$PN"1"
$PIN_NUMBER"?"38;
%"TP"
"1","(-6550,1900)","6","pure_quanta","I243";
;
LOCATION"TP15"
$SEC"1"
CDS_SEC"1"
MATERIAL"NA"
PACK_TYPE"TP"
CDS_LIB"pure_quanta"
PART_NUMBER"TP30";
"TP \B"
$PN"1"
$PIN_NUMBER"?"119;
%"TP"
"1","(-6675,1900)","6","pure_quanta","I244";
;
LOCATION"TP14"
$SEC"1"
CDS_SEC"1"
MATERIAL"NA"
PACK_TYPE"TP"
CDS_LIB"pure_quanta"
PART_NUMBER"TP30";
"TP \B"
$PN"1"
$PIN_NUMBER"?"120;
%"TP"
"1","(-6750,1900)","6","pure_quanta","I245";
;
LOCATION"TP13"
$SEC"1"
CDS_SEC"1"
MATERIAL"NA"
PACK_TYPE"TP"
CDS_LIB"pure_quanta"
PART_NUMBER"TP30";
"TP \B"
$PN"1"
$PIN_NUMBER"?"121;
%"TP"
"1","(-6825,1900)","6","pure_quanta","I272";
;
LOCATION"TP12"
$SEC"1"
CDS_SEC"1"
MATERIAL"NA"
PACK_TYPE"TP"
CDS_LIB"pure_quanta"
PART_NUMBER"TP30";
"TP \B"
$PN"1"
$PIN_NUMBER"?"37;
%"TP"
"1","(-6900,1900)","6","pure_quanta","I273";
;
LOCATION"TP11"
$SEC"1"
CDS_SEC"1"
MATERIAL"NA"
PACK_TYPE"TP"
CDS_LIB"pure_quanta"
PART_NUMBER"TP30";
"TP \B"
$PN"1"
$PIN_NUMBER"?"122;
%"UNIVERSAL_POWER"
"1","(-8750,5000)","0","pure_quanta_power","I286";
;
HDL_POWER"PVDD18_S5_P1"
CDS_LIB"pure_quanta_power";
"A"2;
%"GND"
"1","(-8625,4275)","0","pure_quanta_power","I289";
;
CDS_LIB"pure_quanta_power"
SIZE"1B"
HDL_POWER"GND";
"A<SIZE-1..0>\NAC"3;
%"GND"
"1","(-8750,4275)","0","pure_quanta_power","I291";
;
CDS_LIB"pure_quanta_power"
SIZE"1B"
HDL_POWER"GND";
"A<SIZE-1..0>\NAC"4;
%"Q_RES"
"2","(-6725,1325)","0","pure_quanta","I308";
;
LOCATION"R528"
$SEC"1"
CDS_SEC"1"
TOLERANCE"1%"
WATTAGE"1/16W"
MATERIAL"CHIP"
VALUE"1K"
PACK_TYPE"0402LF"
CDS_LIB"pure_quanta"
PART_NUMBER"CS21002FB06";
"A"
$PN"1"20;
"B"
$PN"2"153;
%"Q_RES"
"2","(-7000,1325)","0","pure_quanta","I309";
;
LOCATION"R527"
$SEC"1"
CDS_SEC"1"
TOLERANCE"1%"
WATTAGE"1/16W"
MATERIAL"CHIP"
VALUE"1K"
PACK_TYPE"0402LF"
CDS_LIB"pure_quanta"
PART_NUMBER"CS21002FB06";
"A"
$PN"1"20;
"B"
$PN"2"154;
%"Q_CAP"
"1","(-6725,625)","0","pure_quanta","I310";
;
LOCATION"C235"
$SEC"1"
CDS_SEC"1"
PACK_TYPE"C0402"
VOLTAGE"50V"
VALUE"0.001UF"
TOLERANCE"10%"
MATERIAL"EMPTY"
CDS_LIB"pure_quanta"
PART_NUMBER"CH30106KB19";
"B"
$PN"2"5;
"A"
$PN"1"153;
%"Q_CAP"
"1","(-7000,625)","0","pure_quanta","I311";
;
LOCATION"C234"
$SEC"1"
CDS_SEC"1"
PACK_TYPE"C0402"
VOLTAGE"50V"
VALUE"0.001UF"
TOLERANCE"10%"
MATERIAL"EMPTY"
CDS_LIB"pure_quanta"
PART_NUMBER"CH30106KB19";
"B"
$PN"2"6;
"A"
$PN"1"154;
%"GND"
"1","(-6725,325)","0","pure_quanta_power","I312";
;
CDS_LIB"pure_quanta_power"
SIZE"1B"
HDL_POWER"GND";
"A<SIZE-1..0>\NAC"5;
%"GND"
"1","(-7000,325)","0","pure_quanta_power","I313";
;
SIZE"1B"
CDS_LIB"pure_quanta_power"
HDL_POWER"GND";
"A<SIZE-1..0>\NAC"6;
%"Q_RES"
"2","(-7300,1325)","0","pure_quanta","I314";
;
LOCATION"R526"
$SEC"1"
CDS_SEC"1"
TOLERANCE"1%"
WATTAGE"1/16W"
MATERIAL"CHIP"
VALUE"1K"
PACK_TYPE"0402LF"
CDS_LIB"pure_quanta"
PART_NUMBER"CS21002FB06";
"A"
$PN"1"20;
"B"
$PN"2"155;
%"Q_CAP"
"1","(-7300,625)","0","pure_quanta","I315";
;
LOCATION"C233"
$SEC"1"
CDS_SEC"1"
PACK_TYPE"C0402"
VOLTAGE"50V"
VALUE"0.001UF"
TOLERANCE"10%"
MATERIAL"EMPTY"
CDS_LIB"pure_quanta"
PART_NUMBER"CH30106KB19";
"B"
$PN"2"7;
"A"
$PN"1"155;
%"Q_RES"
"2","(-7625,1325)","0","pure_quanta","I316";
;
LOCATION"R525"
$SEC"1"
CDS_SEC"1"
TOLERANCE"1%"
WATTAGE"1/16W"
MATERIAL"CHIP"
VALUE"1K"
PACK_TYPE"0402LF"
CDS_LIB"pure_quanta"
PART_NUMBER"CS21002FB06";
"A"
$PN"1"20;
"B"
$PN"2"156;
%"Q_RES"
"2","(-7950,1325)","0","pure_quanta","I317";
;
LOCATION"R524"
$SEC"1"
CDS_SEC"1"
TOLERANCE"1%"
WATTAGE"1/16W"
MATERIAL"CHIP"
VALUE"1K"
PACK_TYPE"0402LF"
CDS_LIB"pure_quanta"
PART_NUMBER"CS21002FB06";
"A"
$PN"1"20;
"B"
$PN"2"151;
%"Q_CAP"
"1","(-7625,625)","0","pure_quanta","I318";
;
LOCATION"C232"
$SEC"1"
CDS_SEC"1"
PACK_TYPE"C0402"
VOLTAGE"50V"
VALUE"0.001UF"
TOLERANCE"10%"
MATERIAL"EMPTY"
CDS_LIB"pure_quanta"
PART_NUMBER"CH30106KB19";
"B"
$PN"2"8;
"A"
$PN"1"156;
%"Q_CAP"
"1","(-7950,625)","0","pure_quanta","I319";
;
LOCATION"C231"
$SEC"1"
CDS_SEC"1"
PACK_TYPE"C0402"
VOLTAGE"50V"
VALUE"0.001UF"
TOLERANCE"10%"
MATERIAL"EMPTY"
CDS_LIB"pure_quanta"
PART_NUMBER"CH30106KB19";
"B"
$PN"2"9;
"A"
$PN"1"151;
%"GND"
"1","(-7300,325)","0","pure_quanta_power","I320";
;
CDS_LIB"pure_quanta_power"
SIZE"1B"
HDL_POWER"GND";
"A<SIZE-1..0>\NAC"7;
%"GND"
"1","(-7625,325)","0","pure_quanta_power","I321";
;
CDS_LIB"pure_quanta_power"
SIZE"1B"
HDL_POWER"GND";
"A<SIZE-1..0>\NAC"8;
%"GND"
"1","(-7950,325)","0","pure_quanta_power","I322";
;
SIZE"1B"
CDS_LIB"pure_quanta_power"
HDL_POWER"GND";
"A<SIZE-1..0>\NAC"9;
%"UNIVERSAL_POWER"
"1","(-8275,1600)","0","pure_quanta_power","I323";
;
HDL_POWER"PVDD18_S5_P1"
CDS_LIB"pure_quanta_power";
"A"20;
%"Q_RES"
"2","(-8275,1325)","0","pure_quanta","I324";
;
LOCATION"R523"
$SEC"1"
CDS_SEC"1"
TOLERANCE"1%"
WATTAGE"1/16W"
MATERIAL"CHIP"
VALUE"1K"
PACK_TYPE"0402LF"
CDS_LIB"pure_quanta"
PART_NUMBER"CS21002FB06";
"A"
$PN"1"20;
"B"
$PN"2"152;
%"Q_CAP"
"1","(-8275,625)","0","pure_quanta","I325";
;
LOCATION"C230"
$SEC"1"
CDS_SEC"1"
PACK_TYPE"C0402"
VOLTAGE"50V"
VALUE"0.001UF"
TOLERANCE"10%"
MATERIAL"EMPTY"
CDS_LIB"pure_quanta"
PART_NUMBER"CH30106KB19";
"B"
$PN"2"10;
"A"
$PN"1"152;
%"GND"
"1","(-8275,325)","0","pure_quanta_power","I332";
;
SIZE"1B"
CDS_LIB"pure_quanta_power"
HDL_POWER"GND";
"A<SIZE-1..0>\NAC"10;
%"Q_RES"
"1","(-6775,5725)","0","pure_quanta","I333";
;
LOCATION"PR170"
$SEC"1"
CDS_SEC"1"
VALUE"0"
CDS_LIB"pure_quanta"
WATTAGE"1/16W"
MATERIAL"CHIP"
TOLERANCE"5%"
PACK_TYPE"0402LF"
PART_NUMBER"CS00002JB13";
"B"
$PN"2"136;
"A"
$PN"1"137;
%"Q_RES"
"1","(-6775,5775)","0","pure_quanta","I334";
;
LOCATION"PR169"
$SEC"1"
CDS_SEC"1"
VALUE"0"
CDS_LIB"pure_quanta"
WATTAGE"1/16W"
MATERIAL"CHIP"
TOLERANCE"5%"
PACK_TYPE"0402LF"
PART_NUMBER"CS00002JB13";
"B"
$PN"2"138;
"A"
$PN"1"139;
%"Q_RES"
"1","(-6775,5525)","0","pure_quanta","I337";
;
LOCATION"PR237"
$SEC"1"
CDS_SEC"1"
VALUE"0"
CDS_LIB"pure_quanta"
WATTAGE"1/16W"
MATERIAL"CHIP"
TOLERANCE"5%"
PACK_TYPE"0402LF"
PART_NUMBER"CS00002JB13";
"B"
$PN"2"140;
"A"
$PN"1"141;
%"Q_RES"
"1","(-6775,5575)","0","pure_quanta","I338";
;
LOCATION"PR236"
$SEC"1"
CDS_SEC"1"
VALUE"0"
CDS_LIB"pure_quanta"
WATTAGE"1/16W"
MATERIAL"CHIP"
TOLERANCE"5%"
PACK_TYPE"0402LF"
PART_NUMBER"CS00002JB13";
"B"
$PN"2"142;
"A"
$PN"1"143;
%"Q_RES"
"1","(-3100,4775)","0","pure_quanta","I361";
;
LOCATION"R618"
$SEC"1"
CDS_SEC"1"
VALUE"0"
CDS_LIB"pure_quanta"
WATTAGE"1/16W"
MATERIAL"CHIP"
TOLERANCE"5%"
PACK_TYPE"0402LF"
PART_NUMBER"CS00002JB13";
"B"
$PN"2"144;
"A"
$PN"1"34;
%"Q_RES"
"1","(-3100,4825)","0","pure_quanta","I362";
;
LOCATION"R486"
$SEC"1"
CDS_SEC"1"
VALUE"0"
CDS_LIB"pure_quanta"
WATTAGE"1/16W"
MATERIAL"CHIP"
TOLERANCE"5%"
PACK_TYPE"0402LF"
PART_NUMBER"CS00002JB13";
"B"
$PN"2"145;
"A"
$PN"1"146;
%"Q_RES"
"1","(-3100,4675)","0","pure_quanta","I363";
;
LOCATION"R928"
$SEC"1"
CDS_SEC"1"
VALUE"0"
CDS_LIB"pure_quanta"
WATTAGE"1/16W"
MATERIAL"CHIP"
TOLERANCE"5%"
PACK_TYPE"0402LF"
PART_NUMBER"CS00002JB13";
"B"
$PN"2"147;
"A"
$PN"1"33;
%"Q_RES"
"1","(-3100,4725)","0","pure_quanta","I364";
;
LOCATION"R862"
$SEC"1"
CDS_SEC"1"
VALUE"0"
CDS_LIB"pure_quanta"
WATTAGE"1/16W"
MATERIAL"CHIP"
TOLERANCE"5%"
PACK_TYPE"0402LF"
PART_NUMBER"CS00002JB13";
"B"
$PN"2"148;
"A"
$PN"1"149;
%"UNIVERSAL_GND"
"1","(-675,2300)","0","pure_quanta_power","I365";
;
CDS_LIB"pure_quanta_power"
HDL_POWER"GND";
"A"19;
%"UNIVERSAL_GND"
"1","(-150,3350)","0","pure_quanta_power","I370";
;
CDS_LIB"pure_quanta_power"
HDL_POWER"GND";
"A"18;
%"Q_RES"
"1","(-1425,3650)","0","pure_quanta","I371";
;
LOCATION"R929"
$SEC"1"
CDS_SEC"1"
VALUE"0"
CDS_LIB"pure_quanta"
WATTAGE"1/16W"
MATERIAL"CHIP"
TOLERANCE"5%"
PACK_TYPE"0402LF"
PART_NUMBER"CS00002JB13";
"B"
$PN"2"166;
"A"
$PN"1"162;
%"Q_RES"
"1","(-1425,3600)","0","pure_quanta","I372";
;
LOCATION"R930"
$SEC"1"
CDS_SEC"1"
VALUE"0"
CDS_LIB"pure_quanta"
WATTAGE"1/16W"
MATERIAL"CHIP"
TOLERANCE"5%"
PACK_TYPE"0402LF"
PART_NUMBER"CS00002JB13";
"B"
$PN"2"165;
"A"
$PN"1"161;
%"Q_RES"
"1","(-1425,3500)","0","pure_quanta","I373";
;
LOCATION"R932"
$SEC"1"
CDS_SEC"1"
VALUE"0"
CDS_LIB"pure_quanta"
WATTAGE"1/16W"
MATERIAL"CHIP"
TOLERANCE"5%"
PACK_TYPE"0402LF"
PART_NUMBER"CS00002JB13";
"B"
$PN"2"163;
"A"
$PN"1"160;
%"Q_RES"
"1","(-1425,3550)","0","pure_quanta","I374";
;
LOCATION"R931"
$SEC"1"
CDS_SEC"1"
VALUE"0"
CDS_LIB"pure_quanta"
WATTAGE"1/16W"
MATERIAL"CHIP"
TOLERANCE"5%"
PACK_TYPE"0402LF"
PART_NUMBER"CS00002JB13";
"B"
$PN"2"164;
"A"
$PN"1"150;
%"Q_RES"
"1","(-8750,3275)","0","pure_quanta","I387";
;
LOCATION"R517"
$SEC"1"
CDS_SEC"1"
VALUE"2.2K"
PACK_TYPE"0402LF"
TOLERANCE"5%"
MATERIAL"CHIP"
WATTAGE"1/16W"
CDS_LIB"pure_quanta"
PART_NUMBER"CS22202JB07";
"B"
$PN"2"129;
"A"
$PN"1"17;
%"Q_RES"
"1","(-8750,3325)","0","pure_quanta","I388";
;
LOCATION"R522"
$SEC"1"
CDS_SEC"1"
VALUE"2.2K"
PACK_TYPE"0402LF"
TOLERANCE"5%"
MATERIAL"CHIP"
WATTAGE"1/16W"
CDS_LIB"pure_quanta"
PART_NUMBER"CS22202JB07";
"B"
$PN"2"27;
"A"
$PN"1"17;
%"UNIVERSAL_POWER"
"1","(-9050,3600)","0","pure_quanta_power","I389";
;
HDL_POWER"P3V3_AUX"
CDS_LIB"pure_quanta_power";
"A"17;
%"Q_RES"
"1","(-8750,3175)","0","pure_quanta","I390";
;
LOCATION"R513"
$SEC"1"
CDS_SEC"1"
VALUE"2.2K"
PACK_TYPE"0402LF"
TOLERANCE"5%"
MATERIAL"CHIP"
WATTAGE"1/16W"
CDS_LIB"pure_quanta"
PART_NUMBER"CS22202JB07";
"B"
$PN"2"127;
"A"
$PN"1"17;
%"Q_RES"
"1","(-8750,3225)","0","pure_quanta","I391";
;
LOCATION"R515"
$SEC"1"
CDS_SEC"1"
VALUE"2.2K"
PACK_TYPE"0402LF"
TOLERANCE"5%"
MATERIAL"CHIP"
WATTAGE"1/16W"
CDS_LIB"pure_quanta"
PART_NUMBER"CS22202JB07";
"B"
$PN"2"128;
"A"
$PN"1"17;
%"Q_RES"
"1","(-500,5575)","0","pure_quanta","I396";
;
LOCATION"R520"
$SEC"1"
CDS_SEC"1"
VALUE"2.2K"
WATTAGE"1/16W"
MATERIAL"CHIP"
TOLERANCE"5%"
PACK_TYPE"0402LF"
CDS_LIB"pure_quanta"
PART_NUMBER"CS22202JB07";
"B"
$PN"2"14;
"A"
$PN"1"22;
%"Q_RES"
"1","(-500,5875)","0","pure_quanta","I398";
;
LOCATION"R535"
$SEC"1"
CDS_SEC"1"
VALUE"2.2K"
CDS_LIB"pure_quanta"
WATTAGE"1/16W"
MATERIAL"CHIP"
TOLERANCE"5%"
PACK_TYPE"0402LF"
PART_NUMBER"CS22202JB07";
"B"
$PN"2"14;
"A"
$PN"1"15;
%"Q_RES"
"1","(-8750,3025)","0","pure_quanta","I400";
;
LOCATION"R512"
$SEC"1"
CDS_SEC"1"
VALUE"2.2K"
PACK_TYPE"0402LF"
TOLERANCE"5%"
MATERIAL"CHIP"
WATTAGE"1/16W"
CDS_LIB"pure_quanta"
PART_NUMBER"CS22202JB07";
"B"
$PN"2"124;
"A"
$PN"1"17;
%"Q_RES"
"1","(-8750,3075)","0","pure_quanta","I401";
;
LOCATION"R514"
$SEC"1"
CDS_SEC"1"
VALUE"2.2K"
PACK_TYPE"0402LF"
TOLERANCE"5%"
MATERIAL"CHIP"
WATTAGE"1/16W"
CDS_LIB"pure_quanta"
PART_NUMBER"CS22202JB07";
"B"
$PN"2"125;
"A"
$PN"1"17;
%"Q_RES"
"1","(-8750,3125)","0","pure_quanta","I402";
;
LOCATION"R516"
$SEC"1"
CDS_SEC"1"
VALUE"2.2K"
PACK_TYPE"0402LF"
TOLERANCE"5%"
MATERIAL"CHIP"
WATTAGE"1/16W"
CDS_LIB"pure_quanta"
PART_NUMBER"CS22202JB07";
"B"
$PN"2"126;
"A"
$PN"1"17;
%"Q_RES"
"2","(-8750,4825)","2","pure_quanta","I403";
;
LOCATION"R518"
$SEC"1"
CDS_SEC"1"
PACK_TYPE"0402LF"
VALUE"2.2K"
MATERIAL"CHIP"
TOLERANCE"5%"
WATTAGE"1/16W"
CDS_LIB"pure_quanta"
PART_NUMBER"CS22202JB07";
"A"
$PN"1"2;
"B"
$PN"2"131;
%"Q_RES"
"2","(-8750,4475)","2","pure_quanta","I404";
;
LOCATION"R519"
$SEC"1"
CDS_SEC"1"
PACK_TYPE"0402LF"
VALUE"2.2K"
MATERIAL"EMPTY"
TOLERANCE"5%"
WATTAGE"1/16W"
CDS_LIB"pure_quanta"
PART_NUMBER"CS22202JB07";
"A"
$PN"1"131;
"B"
$PN"2"4;
%"Q_RES"
"2","(-8625,4475)","0","pure_quanta","I405";
;
LOCATION"R521"
$SEC"1"
CDS_SEC"1"
PACK_TYPE"0402LF"
VALUE"2.2K"
MATERIAL"CHIP"
TOLERANCE"5%"
WATTAGE"1/16W"
CDS_LIB"pure_quanta"
PART_NUMBER"CS22202JB07";
"A"
$PN"1"130;
"B"
$PN"2"3;
%"Q_RES"
"1","(-500,6075)","0","pure_quanta","I406";
;
LOCATION"R531"
$SEC"1"
CDS_SEC"1"
VALUE"2.2K"
PACK_TYPE"0402LF"
TOLERANCE"5%"
MATERIAL"CHIP"
WATTAGE"1/16W"
CDS_LIB"pure_quanta"
PART_NUMBER"CS22202JB07";
"B"
$PN"2"14;
"A"
$PN"1"11;
%"Q_RES"
"1","(-500,6025)","0","pure_quanta","I407";
;
LOCATION"R532"
$SEC"1"
CDS_SEC"1"
VALUE"2.2K"
PACK_TYPE"0402LF"
TOLERANCE"5%"
MATERIAL"CHIP"
WATTAGE"1/16W"
CDS_LIB"pure_quanta"
PART_NUMBER"CS22202JB07";
"B"
$PN"2"14;
"A"
$PN"1"12;
%"Q_RES"
"1","(-500,5975)","0","pure_quanta","I408";
;
LOCATION"R533"
$SEC"1"
CDS_SEC"1"
VALUE"2.2K"
PACK_TYPE"0402LF"
TOLERANCE"5%"
MATERIAL"CHIP"
WATTAGE"1/16W"
CDS_LIB"pure_quanta"
PART_NUMBER"CS22202JB07";
"B"
$PN"2"14;
"A"
$PN"1"16;
%"Q_RES"
"1","(-500,5925)","0","pure_quanta","I409";
;
LOCATION"R534"
$SEC"1"
CDS_SEC"1"
VALUE"2.2K"
PACK_TYPE"0402LF"
TOLERANCE"5%"
MATERIAL"CHIP"
WATTAGE"1/16W"
CDS_LIB"pure_quanta"
PART_NUMBER"CS22202JB07";
"B"
$PN"2"14;
"A"
$PN"1"13;
%"Q_RES"
"1","(-500,5775)","0","pure_quanta","I410";
;
LOCATION"R537"
$SEC"1"
CDS_SEC"1"
VALUE"2.2K"
PACK_TYPE"0402LF"
TOLERANCE"5%"
MATERIAL"CHIP"
WATTAGE"1/16W"
CDS_LIB"pure_quanta"
PART_NUMBER"CS22202JB07";
"B"
$PN"2"14;
"A"
$PN"1"24;
%"Q_RES"
"1","(-500,5725)","0","pure_quanta","I411";
;
LOCATION"R538"
$SEC"1"
CDS_SEC"1"
VALUE"2.2K"
PACK_TYPE"0402LF"
TOLERANCE"5%"
MATERIAL"CHIP"
WATTAGE"1/16W"
CDS_LIB"pure_quanta"
PART_NUMBER"CS22202JB07";
"B"
$PN"2"14;
"A"
$PN"1"23;
%"Q_RES"
"1","(-500,5675)","0","pure_quanta","I412";
;
LOCATION"R539"
$SEC"1"
CDS_SEC"1"
VALUE"2.2K"
PACK_TYPE"0402LF"
TOLERANCE"5%"
MATERIAL"CHIP"
WATTAGE"1/16W"
CDS_LIB"pure_quanta"
PART_NUMBER"CS22202JB07";
"B"
$PN"2"14;
"A"
$PN"1"25;
%"Q_RES"
"1","(-500,5625)","0","pure_quanta","I413";
;
LOCATION"R540"
$SEC"1"
CDS_SEC"1"
VALUE"2.2K"
PACK_TYPE"0402LF"
TOLERANCE"5%"
MATERIAL"CHIP"
WATTAGE"1/16W"
CDS_LIB"pure_quanta"
PART_NUMBER"CS22202JB07";
"B"
$PN"2"14;
"A"
$PN"1"21;
%"Q_RES"
"1","(-3100,4975)","0","pure_quanta","I415";
;
LOCATION"R488"
$SEC"1"
CDS_SEC"1"
VALUE"33"
PACK_TYPE"0402LF"
TOLERANCE"5%"
MATERIAL"CHIP"
WATTAGE"1/16W"
CDS_LIB"pure_quanta"
BOM_COST"MEM"
PART_NUMBER"CS03302JB10";
"B"
$PN"2"158;
"A"
$PN"1"159;
%"Q_RES"
"1","(-3100,5125)","0","pure_quanta","I417";
;
LOCATION"R497"
$SEC"1"
CDS_SEC"1"
VALUE"33"
PACK_TYPE"0402LF"
TOLERANCE"5%"
MATERIAL"CHIP"
WATTAGE"1/16W"
CDS_LIB"pure_quanta"
BOM_COST"MEM"
PART_NUMBER"CS03302JB10";
"B"
$PN"2"35;
"A"
$PN"1"157;
%"SCONN8_G802M0083150RD3HR"
"1","(-500,3575)","0","pure_quanta","I418";
;
LOCATION"J7"
SEC"1"
VALUE"SCONN8_G802M0083150RD3HR"
MATERIAL"IO"
PART_TYPE"SMLF"
CDS_LIB"pure_quanta"
NEEDS_NO_SIZE"TRUE"
CDS_LMAN_SYM_OUTLINE"-125,125,125,-125"
SEC_TYPE""
PART_NUMBER"DFHD08MS385";
"8"
$PN"8"18;
"7"
$PN"7"163;
"6"
$PN"6"18;
"5"
$PN"5"164;
"4"
$PN"4"18;
"3"
$PN"3"165;
"2"
$PN"2"18;
"1"
$PN"1"166;
%"SCONN8_G802M0083150RD3HR"
"1","(-1025,2525)","0","pure_quanta","I419";
;
LOCATION"J49"
SEC"1"
MATERIAL"IO"
PART_TYPE"SMLF"
VALUE"SCONN8_G802M0083150RD3HR"
SEC_TYPE""
CDS_LMAN_SYM_OUTLINE"-125,125,125,-125"
NEEDS_NO_SIZE"TRUE"
CDS_LIB"pure_quanta"
PART_NUMBER"DFHD08MS385";
"8"
$PN"8"19;
"7"
$PN"7"167;
"6"
$PN"6"19;
"5"
$PN"5"168;
"4"
$PN"4"19;
"3"
$PN"3"169;
"2"
$PN"2"19;
"1"
$PN"1"170;
%"Q_RES"
"1","(-500,5825)","0","pure_quanta","I421";
;
LOCATION"R536"
$SEC"1"
CDS_SEC"1"
MATERIAL"EMPTY"
VALUE"2.2K"
PACK_TYPE"0402LF"
WATTAGE"1/16W"
TOLERANCE"5%"
CDS_LIB"pure_quanta"
PART_NUMBER"CS22202JB07";
"B"
$PN"2"14;
"A"
$PN"1"26;
END.
